(kicad_pcb
	(version 20260206)
	(generator "pcbnew")
	(generator_version "10.0")
	(general
		(thickness 1.6)
		(legacy_teardrops no)
	)
	(paper "A4")
	(title_block
		(title "Wiwynn_Tioga_Pass_MB.brd")
		(comment 1 "Tioga Pass / footprints 4138-4144 of 4770")
	)
	(layers
		(0 "F.Cu" signal "TOP")
		(4 "In1.Cu" signal "L2GND")
		(6 "In2.Cu" signal "L3")
		(8 "In3.Cu" signal "L4GND")
		(10 "In4.Cu" signal "L5")
		(12 "In5.Cu" signal "L6GND")
		(14 "In6.Cu" signal "L7VCC")
		(16 "In7.Cu" signal "L8VCC")
		(18 "In8.Cu" signal "L9GND")
		(20 "In9.Cu" signal "L10")
		(22 "In10.Cu" signal "L11GND")
		(24 "In11.Cu" signal "L12")
		(26 "In12.Cu" signal "L13GND")
		(2 "B.Cu" signal "BOTTOM")
		(9 "F.Adhes" user "F.Adhesive")
		(11 "B.Adhes" user "B.Adhesive")
		(13 "F.Paste" user "Package Geometry/Pastemask Top")
		(15 "B.Paste" user "Package Geometry/Pastemask Bottom")
		(5 "F.SilkS" user "Ref Des/Silkscreen Top")
		(7 "B.SilkS" user "Ref Des/Silkscreen Bottom")
		(1 "F.Mask" user "Board Geometry/Soldermask Top")
		(3 "B.Mask" user "Board Geometry/Soldermask Bottom")
		(17 "Dwgs.User" user "User.Drawings")
		(19 "Cmts.User" user "User.Comments")
		(21 "Eco1.User" user "User.Eco1")
		(23 "Eco2.User" user "User.Eco2")
		(25 "Edge.Cuts" user "Board Geometry/Outline")
		(27 "Margin" user)
		(31 "F.CrtYd" user "Package Geometry/Place Bound Top")
		(29 "B.CrtYd" user "Package Geometry/Place Bound Bottom")
		(35 "F.Fab" user "Ref Des/Assembly Top")
		(33 "B.Fab" user "Ref Des/Assembly Bottom")
	)
	(footprint ""
		(layer "B.Cu")
		(at 415.9885 -4.318 -90)
		(property "Reference" "R2P21"
			(at 0 0 90)
			(layer "B.SilkS")
			(hide yes)
			(effects
				(font
					(size 1.27 1.27)
				)
				(justify mirror)
			)
		)
		(property "Value" ""
			(at 0 0 90)
			(layer "B.Fab")
			(effects
				(font
					(size 1.27 1.27)
				)
				(justify mirror)
			)
		)
		(duplicate_pad_numbers_are_jumpers no)
		(fp_poly
			(pts
				(xy 0.2794 -0.1016) (xy -0.2794 -0.1016) (xy -0.2794 0.9906) (xy 0.2794 0.9906)
			)
			(stroke
				(width 0)
				(type default)
			)
			(fill no)
			(layer "B.CrtYd")
		)
		(fp_line
			(start -0.2794 0.9906)
			(end -0.2794 -0.1016)
			(stroke
				(width 0.1)
				(type default)
			)
			(layer "B.Fab")
		)
		(fp_line
			(start 0.2794 0.9906)
			(end -0.2794 0.9906)
			(stroke
				(width 0.1)
				(type default)
			)
			(layer "B.Fab")
		)
		(fp_line
			(start -0.2794 -0.1016)
			(end 0.2794 -0.1016)
			(stroke
				(width 0.1)
				(type default)
			)
			(layer "B.Fab")
		)
		(fp_line
			(start 0.2794 -0.1016)
			(end 0.2794 0.9906)
			(stroke
				(width 0.1)
				(type default)
			)
			(layer "B.Fab")
		)
		(pad "1" smd rect
			(at 0 0 90)
			(size 0.508 0.508)
			(layers "B.Cu" "B.Mask" "B.Paste")
			(net "P3V3_STBY")
		)
		(pad "2" smd rect
			(at 0 0.889 90)
			(size 0.508 0.508)
			(layers "B.Cu" "B.Mask" "B.Paste")
			(net "PWRGD_P5V_R")
		)
		(zone
			(layer "B.Cu")
			(hatch none 0.5)
			(connect_pads
				(clearance 0)
			)
			(min_thickness 0.25)
			(keepout
				(tracks not_allowed)
				(vias allowed)
				(pads allowed)
				(copperpour not_allowed)
				(footprints allowed)
			)
			(placement
				(enabled no)
				(sheetname "")
			)
			(fill
				(thermal_gap 0.5)
				(thermal_bridge_width 0.5)
				(island_removal_mode 0)
			)
			(polygon
				(pts
					(xy 415.3535 -4.064) (xy 415.3535 -4.572) (xy 415.7345 -4.572) (xy 415.7345 -4.064)
				)
			)
		)
		(zone
			(layer "B.Cu")
			(hatch none 0.5)
			(connect_pads
				(clearance 0)
			)
			(min_thickness 0.25)
			(keepout
				(tracks allowed)
				(vias not_allowed)
				(pads allowed)
				(copperpour not_allowed)
				(footprints allowed)
			)
			(placement
				(enabled no)
				(sheetname "")
			)
			(fill
				(thermal_gap 0.5)
				(thermal_bridge_width 0.5)
				(island_removal_mode 0)
			)
			(polygon
				(pts
					(xy 415.7345 -4.064) (xy 415.7345 -4.572) (xy 415.3535 -4.572) (xy 415.3535 -4.064)
				)
			)
		)
	)
	(footprint ""
		(layer "B.Cu")
		(at 373.884952 -43.224958)
		(property "Reference" "R2T26"
			(at 0 0 0)
			(layer "B.SilkS")
			(hide yes)
			(effects
				(font
					(size 1.27 1.27)
				)
				(justify mirror)
			)
		)
		(property "Value" ""
			(at 0 0 0)
			(layer "B.Fab")
			(effects
				(font
					(size 1.27 1.27)
				)
				(justify mirror)
			)
		)
		(duplicate_pad_numbers_are_jumpers no)
		(fp_poly
			(pts
				(xy 0.2794 -0.1016) (xy -0.2794 -0.1016) (xy -0.2794 0.9906) (xy 0.2794 0.9906)
			)
			(stroke
				(width 0)
				(type default)
			)
			(fill no)
			(layer "B.CrtYd")
		)
		(fp_line
			(start -0.2794 -0.1016)
			(end 0.2794 -0.1016)
			(stroke
				(width 0.1)
				(type default)
			)
			(layer "B.Fab")
		)
		(fp_line
			(start -0.2794 0.9906)
			(end -0.2794 -0.1016)
			(stroke
				(width 0.1)
				(type default)
			)
			(layer "B.Fab")
		)
		(fp_line
			(start 0.2794 -0.1016)
			(end 0.2794 0.9906)
			(stroke
				(width 0.1)
				(type default)
			)
			(layer "B.Fab")
		)
		(fp_line
			(start 0.2794 0.9906)
			(end -0.2794 0.9906)
			(stroke
				(width 0.1)
				(type default)
			)
			(layer "B.Fab")
		)
		(pad "1" smd rect
			(at 0 0 180)
			(size 0.508 0.508)
			(layers "B.Cu" "B.Mask" "B.Paste")
			(net "PVCCIO_CPU0")
		)
		(pad "2" smd rect
			(at 0 0.889 180)
			(size 0.508 0.508)
			(layers "B.Cu" "B.Mask" "B.Paste")
			(net "H_CPU_ERR1_GTL_R_N")
		)
		(zone
			(layer "B.Cu")
			(hatch none 0.5)
			(connect_pads
				(clearance 0)
			)
			(min_thickness 0.25)
			(keepout
				(tracks allowed)
				(vias not_allowed)
				(pads allowed)
				(copperpour not_allowed)
				(footprints allowed)
			)
			(placement
				(enabled no)
				(sheetname "")
			)
			(fill
				(thermal_gap 0.5)
				(thermal_bridge_width 0.5)
				(island_removal_mode 0)
			)
			(polygon
				(pts
					(xy 374.138952 -42.970958) (xy 373.630952 -42.970958) (xy 373.630952 -42.589958) (xy 374.138952 -42.589958)
				)
			)
		)
		(zone
			(layer "B.Cu")
			(hatch none 0.5)
			(connect_pads
				(clearance 0)
			)
			(min_thickness 0.25)
			(keepout
				(tracks not_allowed)
				(vias allowed)
				(pads allowed)
				(copperpour not_allowed)
				(footprints allowed)
			)
			(placement
				(enabled no)
				(sheetname "")
			)
			(fill
				(thermal_gap 0.5)
				(thermal_bridge_width 0.5)
				(island_removal_mode 0)
			)
			(polygon
				(pts
					(xy 374.138952 -42.589958) (xy 373.630952 -42.589958) (xy 373.630952 -42.970958) (xy 374.138952 -42.970958)
				)
			)
		)
	)
	(footprint ""
		(layer "B.Cu")
		(at 338.7344 -18.16354 -90)
		(property "Reference" "R3T11"
			(at 0 0 90)
			(layer "B.SilkS")
			(hide yes)
			(effects
				(font
					(size 1.27 1.27)
				)
				(justify mirror)
			)
		)
		(property "Value" ""
			(at 0 0 90)
			(layer "B.Fab")
			(effects
				(font
					(size 1.27 1.27)
				)
				(justify mirror)
			)
		)
		(duplicate_pad_numbers_are_jumpers no)
		(fp_rect
			(start 0.2794 0.9906)
			(end -0.2794 -0.1016)
			(stroke
				(width 0)
				(type default)
			)
			(fill no)
			(layer "B.CrtYd")
		)
		(fp_line
			(start -0.2794 0.9906)
			(end -0.2794 -0.1016)
			(stroke
				(width 0.1)
				(type default)
			)
			(layer "B.Fab")
		)
		(fp_line
			(start 0.2794 0.9906)
			(end -0.2794 0.9906)
			(stroke
				(width 0.1)
				(type default)
			)
			(layer "B.Fab")
		)
		(fp_line
			(start -0.2794 -0.1016)
			(end 0.2794 -0.1016)
			(stroke
				(width 0.1)
				(type default)
			)
			(layer "B.Fab")
		)
		(fp_line
			(start 0.2794 -0.1016)
			(end 0.2794 0.9906)
			(stroke
				(width 0.1)
				(type default)
			)
			(layer "B.Fab")
		)
		(pad "1" smd rect
			(at 0 0 90)
			(size 0.508 0.508)
			(layers "B.Cu" "B.Mask" "B.Paste")
			(net "PVCCIO_CPU0")
		)
		(pad "2" smd rect
			(at 0 0.889 90)
			(size 0.508 0.508)
			(layers "B.Cu" "B.Mask" "B.Paste")
			(net "SVID_CLK1_CPU0_R")
		)
		(zone
			(layer "B.Cu")
			(hatch none 0.5)
			(connect_pads
				(clearance 0)
			)
			(min_thickness 0.25)
			(keepout
				(tracks allowed)
				(vias not_allowed)
				(pads allowed)
				(copperpour not_allowed)
				(footprints allowed)
			)
			(placement
				(enabled no)
				(sheetname "")
			)
			(fill
				(thermal_gap 0.5)
				(thermal_bridge_width 0.5)
				(island_removal_mode 0)
			)
			(polygon
				(pts
					(xy 338.0994 -17.90954) (xy 338.4804 -17.90954) (xy 338.4804 -18.41754) (xy 338.0994 -18.41754)
				)
			)
		)
		(zone
			(layer "B.Cu")
			(hatch none 0.5)
			(connect_pads
				(clearance 0)
			)
			(min_thickness 0.25)
			(keepout
				(tracks not_allowed)
				(vias allowed)
				(pads allowed)
				(copperpour not_allowed)
				(footprints allowed)
			)
			(placement
				(enabled no)
				(sheetname "")
			)
			(fill
				(thermal_gap 0.5)
				(thermal_bridge_width 0.5)
				(island_removal_mode 0)
			)
			(polygon
				(pts
					(xy 338.0994 -17.90954) (xy 338.4804 -17.90954) (xy 338.4804 -18.41754) (xy 338.0994 -18.41754)
				)
			)
		)
	)
	(footprint ""
		(layer "B.Cu")
		(at 489.189014 -140.589 90)
		(property "Reference" "Q1L4"
			(at -2.86131 2.27838 0)
			(unlocked yes)
			(layer "B.SilkS")
			(effects
				(font
					(size 0.7874 0.5842)
					(thickness 0.1524)
				)
				(justify left mirror)
			)
		)
		(property "Value" ""
			(at 0 0 90)
			(layer "B.Fab")
			(effects
				(font
					(size 1.27 1.27)
				)
				(justify mirror)
			)
		)
		(duplicate_pad_numbers_are_jumpers no)
		(fp_circle
			(center 0.848614 -0.6477)
			(end 0.848614 -0.5207)
			(stroke
				(width 0.254)
				(type default)
			)
			(fill no)
			(layer "B.SilkS")
		)
		(fp_poly
			(pts
				(xy -0.21463 -0.450088) (xy -1.56337 -0.450088) (xy -1.56337 1.75006) (xy -0.21463 1.75006)
			)
			(stroke
				(width 0)
				(type default)
			)
			(fill no)
			(layer "B.CrtYd")
		)
		(fp_line
			(start -0.21463 -0.450088)
			(end -1.56337 -0.450088)
			(stroke
				(width 0.1)
				(type default)
			)
			(layer "B.Fab")
		)
		(fp_line
			(start -1.56337 -0.450088)
			(end -1.56337 1.75006)
			(stroke
				(width 0.1)
				(type default)
			)
			(layer "B.Fab")
		)
		(fp_line
			(start -0.21463 1.75006)
			(end -0.21463 -0.450088)
			(stroke
				(width 0.1)
				(type default)
			)
			(layer "B.Fab")
		)
		(fp_line
			(start -1.56337 1.75006)
			(end -0.21463 1.75006)
			(stroke
				(width 0.1)
				(type default)
			)
			(layer "B.Fab")
		)
		(fp_circle
			(center 0.848614 -0.6477)
			(end 0.848614 -0.5207)
			(stroke
				(width 0.254)
				(type default)
			)
			(fill no)
			(layer "B.Fab")
		)
		(pad "1" smd rect
			(at 0 0 270)
			(size 1.016 0.381)
			(layers "B.Cu" "B.Mask" "B.Paste")
			(net "GND")
		)
		(pad "2" smd rect
			(at 0 0.649986 270)
			(size 1.016 0.381)
			(layers "B.Cu" "B.Mask" "B.Paste")
			(net "FM_DB_PRESENT")
		)
		(pad "3" smd rect
			(at 0 1.299972 270)
			(size 1.016 0.381)
			(layers "B.Cu" "B.Mask" "B.Paste")
			(net "TP_FET_Q56_3")
		)
		(pad "4" smd rect
			(at -1.778 1.299972 270)
			(size 1.016 0.381)
			(layers "B.Cu" "B.Mask" "B.Paste")
			(net "TP_FET_Q56_4")
		)
		(pad "5" smd rect
			(at -1.778 0.649986 270)
			(size 1.016 0.381)
			(layers "B.Cu" "B.Mask" "B.Paste")
			(net "TP_FET_Q56_4")
		)
		(pad "6" smd rect
			(at -1.778 0 270)
			(size 1.016 0.381)
			(layers "B.Cu" "B.Mask" "B.Paste")
			(net "FM_POST_CARD_PRES_BMC_N")
		)
	)
	(footprint ""
		(layer "B.Cu")
		(at 477.634554 -2.513838 90)
		(property "Reference" "R9G11"
			(at 0 0 90)
			(layer "B.SilkS")
			(hide yes)
			(effects
				(font
					(size 1.27 1.27)
				)
				(justify mirror)
			)
		)
		(property "Value" ""
			(at 0 0 90)
			(layer "B.Fab")
			(effects
				(font
					(size 1.27 1.27)
				)
				(justify mirror)
			)
		)
		(duplicate_pad_numbers_are_jumpers no)
		(fp_poly
			(pts
				(xy 0.2794 -0.1016) (xy -0.2794 -0.1016) (xy -0.2794 0.9906) (xy 0.2794 0.9906)
			)
			(stroke
				(width 0)
				(type default)
			)
			(fill no)
			(layer "B.CrtYd")
		)
		(fp_line
			(start 0.2794 -0.1016)
			(end 0.2794 0.9906)
			(stroke
				(width 0.1)
				(type default)
			)
			(layer "B.Fab")
		)
		(fp_line
			(start -0.2794 -0.1016)
			(end 0.2794 -0.1016)
			(stroke
				(width 0.1)
				(type default)
			)
			(layer "B.Fab")
		)
		(fp_line
			(start 0.2794 0.9906)
			(end -0.2794 0.9906)
			(stroke
				(width 0.1)
				(type default)
			)
			(layer "B.Fab")
		)
		(fp_line
			(start -0.2794 0.9906)
			(end -0.2794 -0.1016)
			(stroke
				(width 0.1)
				(type default)
			)
			(layer "B.Fab")
		)
		(pad "1" smd rect
			(at 0 0 270)
			(size 0.508 0.508)
			(layers "B.Cu" "B.Mask" "B.Paste")
			(net "NIC_SER_N_MDI_3_DN")
		)
		(pad "2" smd rect
			(at 0 0.889 270)
			(size 0.508 0.508)
			(layers "B.Cu" "B.Mask" "B.Paste")
			(net "NIC_MDI_SPRV_RJ45_3_R_DN")
		)
		(zone
			(layer "B.Cu")
			(hatch none 0.5)
			(connect_pads
				(clearance 0)
			)
			(min_thickness 0.25)
			(keepout
				(tracks allowed)
				(vias not_allowed)
				(pads allowed)
				(copperpour not_allowed)
				(footprints allowed)
			)
			(placement
				(enabled no)
				(sheetname "")
			)
			(fill
				(thermal_gap 0.5)
				(thermal_bridge_width 0.5)
				(island_removal_mode 0)
			)
			(polygon
				(pts
					(xy 477.888554 -2.767838) (xy 477.888554 -2.259838) (xy 478.269554 -2.259838) (xy 478.269554 -2.767838)
				)
			)
		)
		(zone
			(layer "B.Cu")
			(hatch none 0.5)
			(connect_pads
				(clearance 0)
			)
			(min_thickness 0.25)
			(keepout
				(tracks not_allowed)
				(vias allowed)
				(pads allowed)
				(copperpour not_allowed)
				(footprints allowed)
			)
			(placement
				(enabled no)
				(sheetname "")
			)
			(fill
				(thermal_gap 0.5)
				(thermal_bridge_width 0.5)
				(island_removal_mode 0)
			)
			(polygon
				(pts
					(xy 478.269554 -2.767838) (xy 478.269554 -2.259838) (xy 477.888554 -2.259838) (xy 477.888554 -2.767838)
				)
			)
		)
	)
	(footprint ""
		(layer "B.Cu")
		(at 402.463 -152.527 -90)
		(property "Reference" "R2L26"
			(at 0 0 90)
			(layer "B.SilkS")
			(hide yes)
			(effects
				(font
					(size 1.27 1.27)
				)
				(justify mirror)
			)
		)
		(property "Value" ""
			(at 0 0 90)
			(layer "B.Fab")
			(effects
				(font
					(size 1.27 1.27)
				)
				(justify mirror)
			)
		)
		(duplicate_pad_numbers_are_jumpers no)
		(fp_poly
			(pts
				(xy 0.2794 -0.1016) (xy -0.2794 -0.1016) (xy -0.2794 0.9906) (xy 0.2794 0.9906)
			)
			(stroke
				(width 0)
				(type default)
			)
			(fill no)
			(layer "B.CrtYd")
		)
		(fp_line
			(start -0.2794 0.9906)
			(end -0.2794 -0.1016)
			(stroke
				(width 0.1)
				(type default)
			)
			(layer "B.Fab")
		)
		(fp_line
			(start 0.2794 0.9906)
			(end -0.2794 0.9906)
			(stroke
				(width 0.1)
				(type default)
			)
			(layer "B.Fab")
		)
		(fp_line
			(start -0.2794 -0.1016)
			(end 0.2794 -0.1016)
			(stroke
				(width 0.1)
				(type default)
			)
			(layer "B.Fab")
		)
		(fp_line
			(start 0.2794 -0.1016)
			(end 0.2794 0.9906)
			(stroke
				(width 0.1)
				(type default)
			)
			(layer "B.Fab")
		)
		(pad "1" smd rect
			(at 0 0 90)
			(size 0.508 0.508)
			(layers "B.Cu" "B.Mask" "B.Paste")
			(net "P3V3_STBY")
		)
		(pad "2" smd rect
			(at 0 0.889 90)
			(size 0.508 0.508)
			(layers "B.Cu" "B.Mask" "B.Paste")
			(net "VID_PCH_CORE_PVNN_AUX_VID_0")
		)
		(zone
			(layer "B.Cu")
			(hatch none 0.5)
			(connect_pads
				(clearance 0)
			)
			(min_thickness 0.25)
			(keepout
				(tracks not_allowed)
				(vias allowed)
				(pads allowed)
				(copperpour not_allowed)
				(footprints allowed)
			)
			(placement
				(enabled no)
				(sheetname "")
			)
			(fill
				(thermal_gap 0.5)
				(thermal_bridge_width 0.5)
				(island_removal_mode 0)
			)
			(polygon
				(pts
					(xy 401.828 -152.273) (xy 401.828 -152.781) (xy 402.209 -152.781) (xy 402.209 -152.273)
				)
			)
		)
		(zone
			(layer "B.Cu")
			(hatch none 0.5)
			(connect_pads
				(clearance 0)
			)
			(min_thickness 0.25)
			(keepout
				(tracks allowed)
				(vias not_allowed)
				(pads allowed)
				(copperpour not_allowed)
				(footprints allowed)
			)
			(placement
				(enabled no)
				(sheetname "")
			)
			(fill
				(thermal_gap 0.5)
				(thermal_bridge_width 0.5)
				(island_removal_mode 0)
			)
			(polygon
				(pts
					(xy 402.209 -152.273) (xy 402.209 -152.781) (xy 401.828 -152.781) (xy 401.828 -152.273)
				)
			)
		)
	)
	(footprint ""
		(layer "B.Cu")
		(at 30.9372 -88.7222)
		(property "Reference" "CT15"
			(at 0.8382 -0.84963 0)
			(unlocked yes)
			(layer "B.SilkS")
			(effects
				(font
					(size 0.7874 0.5842)
					(thickness 0.1524)
				)
				(justify left mirror)
			)
		)
		(property "Value" ""
			(at 0 0 0)
			(layer "B.Fab")
			(effects
				(font
					(size 1.27 1.27)
				)
				(justify mirror)
			)
		)
		(duplicate_pad_numbers_are_jumpers no)
		(fp_poly
			(pts
				(xy -0.3048 -0.1016) (xy -0.3048 0.9906) (xy 0.3048 0.9906) (xy 0.3048 -0.1016)
			)
			(stroke
				(width 0)
				(type default)
			)
			(fill no)
			(layer "B.CrtYd")
		)
		(fp_line
			(start -0.3048 -0.1016)
			(end 0.3048 -0.1016)
			(stroke
				(width 0.1)
				(type default)
			)
			(layer "B.Fab")
		)
		(fp_line
			(start -0.3048 0.9906)
			(end -0.3048 -0.1016)
			(stroke
				(width 0.1)
				(type default)
			)
			(layer "B.Fab")
		)
		(fp_line
			(start 0.3048 -0.1016)
			(end 0.3048 0.9906)
			(stroke
				(width 0.1)
				(type default)
			)
			(layer "B.Fab")
		)
		(fp_line
			(start 0.3048 0.9906)
			(end -0.3048 0.9906)
			(stroke
				(width 0.1)
				(type default)
			)
			(layer "B.Fab")
		)
		(pad "1" smd rect
			(at 0 0 180)
			(size 0.508 0.508)
			(layers "B.Cu" "B.Mask" "B.Paste")
			(net "A_TSENSE_PVCCIN_CPU1")
		)
		(pad "2" smd rect
			(at 0 0.889 180)
			(size 0.508 0.508)
			(layers "B.Cu" "B.Mask" "B.Paste")
			(net "GND")
		)
		(zone
			(layer "B.Cu")
			(hatch none 0.5)
			(connect_pads
				(clearance 0)
			)
			(min_thickness 0.25)
			(keepout
				(tracks allowed)
				(vias not_allowed)
				(pads allowed)
				(copperpour not_allowed)
				(footprints allowed)
			)
			(placement
				(enabled no)
				(sheetname "")
			)
			(fill
				(thermal_gap 0.5)
				(thermal_bridge_width 0.5)
				(island_removal_mode 0)
			)
			(polygon
				(pts
					(xy 31.1912 -88.4682) (xy 30.6832 -88.4682) (xy 30.6832 -88.0872) (xy 31.1912 -88.0872)
				)
			)
		)
		(zone
			(layer "B.Cu")
			(hatch none 0.5)
			(connect_pads
				(clearance 0)
			)
			(min_thickness 0.25)
			(keepout
				(tracks not_allowed)
				(vias allowed)
				(pads allowed)
				(copperpour not_allowed)
				(footprints allowed)
			)
			(placement
				(enabled no)
				(sheetname "")
			)
			(fill
				(thermal_gap 0.5)
				(thermal_bridge_width 0.5)
				(island_removal_mode 0)
			)
			(polygon
				(pts
					(xy 31.1912 -88.0872) (xy 30.6832 -88.0872) (xy 30.6832 -88.4682) (xy 31.1912 -88.4682)
				)
			)
		)
	)
)
